FILE_TYPE = MACRO_DRAWING;
SET COLOR_WIRE YELLOW;
SET COLOR_PROP ORANGE;
SET COLOR_DOT WHITE;
SET COLOR_ARC YELLOW;
SET COLOR_BODY GREEN;
SET COLOR_NOTE PURPLE;
SET PROP_DISPLAY VALUE;
SET PAGE_NUMBER P306;
FORCEADD OFFPAGE..1
(-3950 150);
PAINT AQUA (-3950 150);
FORCEPROP 2 LAST $XR1 214 
J 0
(-4202 114);
DISPLAY 0.638298 (-4202 114);
PAINT MONO (-4202 114);
FORCEPROP 2 LAST $XR0 284 
J 0
(-4202 150);
DISPLAY 0.638298 (-4202 150);
PAINT MONO (-4202 150);
FORCEPROP 2 LAST PATH I1
J 0
(-4200 200);
DISPLAY 1.021277 (-4200 200);
DISPLAY INVISIBLE (-4200 200);
FORCEPROP 1 LAST COMMENT_BODY TRUE
J 0
(-3825 50);
DISPLAY 0.872340 (-3825 50);
PAINT GREEN (-3825 50);
DISPLAY INVISIBLE (-3825 50);
FORCEPROP 1 LAST OFFPAGE TRUE
J 0
(-3625 25);
DISPLAY 0.872340 (-3625 25);
PAINT AQUA (-3625 25);
DISPLAY INVISIBLE (-3625 25);
FORCEPROP 2 LAST CDS_LIB standard
J 0
(-3950 150);
DISPLAY INVISIBLE (-3950 150);
FORCEADD UNIVERSAL_GND..1
(-2800 3725);
FORCEPROP 3 LASTPIN (-2800 3775) SIG_NAME GND\g
J 0
(-2790 3785);
DISPLAY 0.659574 (-2790 3785);
PAINT MONO (-2790 3785);
DISPLAY INVISIBLE (-2790 3785);
FORCEPROP 1 LAST PATH I10
J 0
(-2725 3725);
DISPLAY 0.872340 (-2725 3725);
PAINT AQUA (-2725 3725);
DISPLAY INVISIBLE (-2725 3725);
FORCEPROP 1 LAST HDL_POWER GND
J 1
(-2775 3650);
DISPLAY 0.872340 (-2775 3650);
PAINT GREEN (-2775 3650);
DISPLAY INVISIBLE (-2775 3650);
FORCEPROP 2 LAST CDS_LIB logical_power
J 0
(-2800 3725);
DISPLAY INVISIBLE (-2800 3725);
FORCEADD Q_LED..1
R 2
(-1775 475);
FORCEPROP 1 LAST PART_NUMBER BEBL0172Z00
J 0
(-1875 250);
DISPLAY 0.574468 (-1875 250);
PAINT GREEN (-1875 250);
DISPLAY INVISIBLE (-1875 250);
FORCEPROP 0 LAST PACK_TYPE SMLF
J 0
(-1875 300);
DISPLAY 0.638298 (-1875 300);
FORCEPROP 2 LAST COLOR LED_BLUE
J 0
(-1875 350);
DISPLAY 0.638298 (-1875 350);
FORCEPROP 2 LAST MANUF_PN LTST-C281TBKT-5A
J 0
(-1875 200);
DISPLAY 0.638298 (-1875 200);
FORCEPROP 1 LAST MATERIAL IC
J 0
(-1750 300);
DISPLAY 0.723404 (-1750 300);
PAINT GREEN (-1750 300);
FORCEPROP 1 LAST LOCATION D83
J 0
(-1875 400);
DISPLAY 0.723404 (-1875 400);
PAINT GREEN (-1875 400);
FORCEPROP 0 LASTPIN (-1625 475) $PN A
J 0
(-1615 485);
DISPLAY 0.808511 (-1615 485);
FORCEPROP 0 LASTPIN (-1925 475) $PN C
J 2
(-1935 485);
DISPLAY 0.808511 (-1935 485);
FORCEPROP 2 LAST CDS_LIB pure_quanta
J 0
(-1775 475);
DISPLAY INVISIBLE (-1775 475);
FORCEPROP 1 LAST NEEDS_NO_SIZE TRUE
J 2
(-1753 497);
DISPLAY 0.468085 (-1753 497);
PAINT GREEN (-1753 497);
DISPLAY INVISIBLE (-1753 497);
FORCEPROP 1 LAST PATH I11
J 2
(-1900 555);
DISPLAY 0.723404 (-1900 555);
PAINT GREEN (-1900 555);
DISPLAY INVISIBLE (-1900 555);
FORCEPROP 0 LAST $SEC 1
J 0
(-1875 450);
DISPLAY INVISIBLE (-1875 450);
FORCEPROP 0 LAST CDS_SEC 1
J 0
(-1875 450);
DISPLAY INVISIBLE (-1875 450);
FORCEADD Q_RES..1
(-400 475);
FORCEPROP 1 LAST PART_NUMBER CS11302FB03
J 0
(-625 575);
DISPLAY 0.638298 (-625 575);
DISPLAY INVISIBLE (-625 575);
FORCEPROP 1 LAST VALUE 130
J 2
(-200 475);
DISPLAY 0.638298 (-200 475);
FORCEPROP 1 LAST TOLERANCE 1%
J 0
(-175 475);
DISPLAY 0.638298 (-175 475);
FORCEPROP 1 LAST PACK_TYPE 0402LF
J 0
(-100 475);
DISPLAY 0.638298 (-100 475);
FORCEPROP 1 LAST WATTAGE 1/16W
J 2
(-250 425);
DISPLAY 0.638298 (-250 425);
FORCEPROP 1 LAST MATERIAL CHIP
J 0
(-550 425);
DISPLAY 0.638298 (-550 425);
FORCEPROP 1 LAST $LOCATION R3095
J 0
(-450 525);
DISPLAY 0.978723 (-450 525);
FORCEPROP 1 LASTPIN (-500 475) $PN 1
J 0
(-488 487);
DISPLAY 0.787234 (-488 487);
PAINT MONO (-488 487);
FORCEPROP 1 LASTPIN (-300 475) $PN 2
J 0
(-338 487);
DISPLAY 0.787234 (-338 487);
PAINT MONO (-338 487);
FORCEPROP 1 LAST PATH I12
J 0
(-450 625);
DISPLAY 0.978723 (-450 625);
PAINT WHITE (-450 625);
DISPLAY INVISIBLE (-450 625);
FORCEPROP 2 LAST CDS_LIB pure_quanta
J 0
(-400 475);
DISPLAY INVISIBLE (-400 475);
FORCEPROP 0 LAST CDS_LOCATION R3095
J 0
(-450 575);
DISPLAY 1.021277 (-450 575);
DISPLAY INVISIBLE (-450 575);
FORCEPROP 0 LAST $SEC 1
J 0
(-450 575);
DISPLAY 0.680851 (-450 575);
PAINT MONO (-450 575);
DISPLAY INVISIBLE (-450 575);
FORCEPROP 0 LAST CDS_SEC 1
J 0
(-450 575);
DISPLAY 1.021277 (-450 575);
DISPLAY INVISIBLE (-450 575);
FORCEADD Q_LED..1
R 2
(-1775 1800);
FORCEPROP 1 LAST PART_NUMBER BEBL0172Z00
J 0
(-1875 1575);
DISPLAY 0.574468 (-1875 1575);
PAINT GREEN (-1875 1575);
DISPLAY INVISIBLE (-1875 1575);
FORCEPROP 1 LAST MATERIAL IC
J 0
(-1750 1625);
DISPLAY 0.723404 (-1750 1625);
PAINT GREEN (-1750 1625);
FORCEPROP 2 LAST COLOR LED_BLUE
J 0
(-1875 1675);
DISPLAY 0.638298 (-1875 1675);
FORCEPROP 0 LAST PACK_TYPE SMLF
J 0
(-1875 1625);
DISPLAY 0.638298 (-1875 1625);
FORCEPROP 2 LAST MANUF_PN LTST-C281TBKT-5A
J 0
(-1875 1525);
DISPLAY 0.638298 (-1875 1525);
FORCEPROP 1 LAST LOCATION D82
J 0
(-1875 1725);
DISPLAY 0.723404 (-1875 1725);
PAINT GREEN (-1875 1725);
FORCEPROP 0 LASTPIN (-1625 1800) $PN A
J 0
(-1615 1810);
DISPLAY 0.808511 (-1615 1810);
FORCEPROP 0 LASTPIN (-1925 1800) $PN C
J 2
(-1935 1810);
DISPLAY 0.808511 (-1935 1810);
FORCEPROP 1 LAST PATH I13
J 2
(-1900 1880);
DISPLAY 0.723404 (-1900 1880);
PAINT GREEN (-1900 1880);
DISPLAY INVISIBLE (-1900 1880);
FORCEPROP 1 LAST NEEDS_NO_SIZE TRUE
J 2
(-1753 1822);
DISPLAY 0.468085 (-1753 1822);
PAINT GREEN (-1753 1822);
DISPLAY INVISIBLE (-1753 1822);
FORCEPROP 2 LAST CDS_LIB pure_quanta
J 0
(-1775 1800);
DISPLAY INVISIBLE (-1775 1800);
FORCEPROP 0 LAST $SEC 1
J 0
(-1875 1775);
DISPLAY INVISIBLE (-1875 1775);
FORCEPROP 0 LAST CDS_SEC 1
J 0
(-1875 1775);
DISPLAY INVISIBLE (-1875 1775);
FORCEADD Q_LED..1
R 2
(-1775 3025);
FORCEPROP 1 LAST PART_NUMBER BEBL0172Z00
J 0
(-1875 2800);
DISPLAY 0.574468 (-1875 2800);
PAINT GREEN (-1875 2800);
DISPLAY INVISIBLE (-1875 2800);
FORCEPROP 0 LAST PACK_TYPE SMLF
J 0
(-1875 2850);
DISPLAY 0.638298 (-1875 2850);
FORCEPROP 1 LAST MATERIAL IC
J 0
(-1750 2850);
DISPLAY 0.723404 (-1750 2850);
PAINT GREEN (-1750 2850);
FORCEPROP 2 LAST COLOR LED_BLUE
J 0
(-1875 2900);
DISPLAY 0.638298 (-1875 2900);
FORCEPROP 2 LAST MANUF_PN LTST-C281TBKT-5A
J 0
(-1875 2750);
DISPLAY 0.638298 (-1875 2750);
FORCEPROP 1 LAST LOCATION D81
J 0
(-1875 2950);
DISPLAY 0.723404 (-1875 2950);
PAINT GREEN (-1875 2950);
FORCEPROP 0 LASTPIN (-1625 3025) $PN A
J 0
(-1615 3035);
DISPLAY 0.808511 (-1615 3035);
FORCEPROP 0 LASTPIN (-1925 3025) $PN C
J 2
(-1935 3035);
DISPLAY 0.808511 (-1935 3035);
FORCEPROP 1 LAST PATH I14
J 2
(-1900 3105);
DISPLAY 0.723404 (-1900 3105);
PAINT GREEN (-1900 3105);
DISPLAY INVISIBLE (-1900 3105);
FORCEPROP 2 LAST CDS_LIB pure_quanta
J 0
(-1775 3025);
DISPLAY INVISIBLE (-1775 3025);
FORCEPROP 1 LAST NEEDS_NO_SIZE TRUE
J 2
(-1753 3047);
DISPLAY 0.468085 (-1753 3047);
PAINT GREEN (-1753 3047);
DISPLAY INVISIBLE (-1753 3047);
FORCEPROP 0 LAST $SEC 1
J 0
(-1875 3000);
DISPLAY INVISIBLE (-1875 3000);
FORCEPROP 0 LAST CDS_SEC 1
J 0
(-1875 3000);
DISPLAY INVISIBLE (-1875 3000);
FORCEADD Q_RES..1
(-350 1800);
FORCEPROP 1 LAST PART_NUMBER CS11302FB03
J 0
(-575 1900);
DISPLAY 0.638298 (-575 1900);
DISPLAY INVISIBLE (-575 1900);
FORCEPROP 1 LAST VALUE 130
J 2
(-150 1800);
DISPLAY 0.638298 (-150 1800);
FORCEPROP 1 LAST TOLERANCE 1%
J 0
(-125 1800);
DISPLAY 0.638298 (-125 1800);
FORCEPROP 1 LAST MATERIAL CHIP
J 0
(-500 1750);
DISPLAY 0.638298 (-500 1750);
FORCEPROP 1 LAST WATTAGE 1/16W
J 2
(-200 1750);
DISPLAY 0.638298 (-200 1750);
FORCEPROP 1 LAST PACK_TYPE 0402LF
J 0
(-50 1800);
DISPLAY 0.638298 (-50 1800);
FORCEPROP 1 LAST $LOCATION R3096
J 0
(-400 1850);
DISPLAY 0.978723 (-400 1850);
FORCEPROP 1 LASTPIN (-450 1800) $PN 1
J 0
(-438 1812);
DISPLAY 0.787234 (-438 1812);
PAINT MONO (-438 1812);
FORCEPROP 1 LASTPIN (-250 1800) $PN 2
J 0
(-288 1812);
DISPLAY 0.787234 (-288 1812);
PAINT MONO (-288 1812);
FORCEPROP 1 LAST PATH I15
J 0
(-400 1950);
DISPLAY 0.978723 (-400 1950);
PAINT WHITE (-400 1950);
DISPLAY INVISIBLE (-400 1950);
FORCEPROP 2 LAST CDS_LIB pure_quanta
J 0
(-350 1800);
DISPLAY INVISIBLE (-350 1800);
FORCEPROP 0 LAST CDS_LOCATION R3096
J 0
(-400 1900);
DISPLAY 1.021277 (-400 1900);
DISPLAY INVISIBLE (-400 1900);
FORCEPROP 0 LAST $SEC 1
J 0
(-400 1900);
DISPLAY 0.680851 (-400 1900);
PAINT MONO (-400 1900);
DISPLAY INVISIBLE (-400 1900);
FORCEPROP 0 LAST CDS_SEC 1
J 0
(-400 1900);
DISPLAY 1.021277 (-400 1900);
DISPLAY INVISIBLE (-400 1900);
FORCEADD Q_RES..1
(-400 3025);
FORCEPROP 1 LAST PART_NUMBER CS11302FB03
J 0
(-625 3125);
DISPLAY 0.638298 (-625 3125);
DISPLAY INVISIBLE (-625 3125);
FORCEPROP 1 LAST VALUE 130
J 2
(-200 3025);
DISPLAY 0.638298 (-200 3025);
FORCEPROP 1 LAST TOLERANCE 1%
J 0
(-175 3025);
DISPLAY 0.638298 (-175 3025);
FORCEPROP 1 LAST MATERIAL CHIP
J 0
(-550 2975);
DISPLAY 0.638298 (-550 2975);
FORCEPROP 1 LAST WATTAGE 1/16W
J 2
(-250 2975);
DISPLAY 0.638298 (-250 2975);
FORCEPROP 1 LAST PACK_TYPE 0402LF
J 0
(-100 3025);
DISPLAY 0.638298 (-100 3025);
FORCEPROP 1 LAST $LOCATION R3094
J 0
(-450 3075);
DISPLAY 0.978723 (-450 3075);
FORCEPROP 1 LASTPIN (-500 3025) $PN 1
J 0
(-488 3037);
DISPLAY 0.787234 (-488 3037);
PAINT MONO (-488 3037);
FORCEPROP 1 LASTPIN (-300 3025) $PN 2
J 0
(-338 3037);
DISPLAY 0.787234 (-338 3037);
PAINT MONO (-338 3037);
FORCEPROP 1 LAST PATH I16
J 0
(-450 3175);
DISPLAY 0.978723 (-450 3175);
PAINT WHITE (-450 3175);
DISPLAY INVISIBLE (-450 3175);
FORCEPROP 2 LAST CDS_LIB pure_quanta
J 0
(-400 3025);
DISPLAY INVISIBLE (-400 3025);
FORCEPROP 0 LAST CDS_LOCATION R3094
J 0
(-450 3125);
DISPLAY 1.021277 (-450 3125);
DISPLAY INVISIBLE (-450 3125);
FORCEPROP 0 LAST $SEC 1
J 0
(-450 3125);
DISPLAY 0.680851 (-450 3125);
PAINT MONO (-450 3125);
DISPLAY INVISIBLE (-450 3125);
FORCEPROP 0 LAST CDS_SEC 1
J 0
(-450 3125);
DISPLAY 1.021277 (-450 3125);
DISPLAY INVISIBLE (-450 3125);
FORCEADD OFFPAGE..1
(-3950 4025);
PAINT AQUA (-3950 4025);
FORCEPROP 2 LAST $XR1 214 
J 0
(-4202 3989);
DISPLAY 0.638298 (-4202 3989);
PAINT MONO (-4202 3989);
FORCEPROP 2 LAST $XR0 296 
J 0
(-4202 4025);
DISPLAY 0.638298 (-4202 4025);
PAINT MONO (-4202 4025);
FORCEPROP 2 LAST PATH I17
J 0
(-4200 4075);
DISPLAY 1.021277 (-4200 4075);
DISPLAY INVISIBLE (-4200 4075);
FORCEPROP 1 LAST COMMENT_BODY TRUE
J 0
(-3825 3925);
DISPLAY 0.872340 (-3825 3925);
PAINT GREEN (-3825 3925);
DISPLAY INVISIBLE (-3825 3925);
FORCEPROP 1 LAST OFFPAGE TRUE
J 0
(-3625 3900);
DISPLAY 0.872340 (-3625 3900);
PAINT AQUA (-3625 3900);
DISPLAY INVISIBLE (-3625 3900);
FORCEPROP 2 LAST CDS_LIB standard
J 0
(-3950 4025);
DISPLAY INVISIBLE (-3950 4025);
FORCEADD MOSFET_NCH_DUAL..1
(-2850 4075);
FORCEPROP 1 LAST PART_NUMBER BAM138K0003
J 0
(-2699 3989);
DISPLAY 0.723404 (-2699 3989);
PAINT GREEN (-2699 3989);
DISPLAY INVISIBLE (-2699 3989);
FORCEPROP 2 LAST VALUE PJT138K
J 0
(-2675 4100);
DISPLAY 1.021277 (-2675 4100);
FORCEPROP 1 LAST MATERIAL IC
J 0
(-2699 3924);
DISPLAY 0.723404 (-2699 3924);
PAINT GREEN (-2699 3924);
FORCEPROP 2 LAST PART_TYPE SMLF
J 0
(-2675 4150);
DISPLAY 1.021277 (-2675 4150);
FORCEPROP 1 LAST LOCATION Q84
J 0
(-2699 4049);
DISPLAY 0.723404 (-2699 4049);
PAINT GREEN (-2699 4049);
FORCEPROP 0 LASTPIN (-2800 4275) $PN 6
R 1
J 0
(-2810 4285);
DISPLAY 0.808511 (-2810 4285);
FORCEPROP 0 LASTPIN (-3050 4025) $PN 2
J 2
(-3060 4035);
DISPLAY 0.808511 (-3060 4035);
FORCEPROP 0 LASTPIN (-2800 3875) $PN 1
R 1
J 2
(-2810 3865);
DISPLAY 0.808511 (-2810 3865);
FORCEPROP 1 LAST PATH I18
J 0
(-2850 4075);
DISPLAY 0.723404 (-2850 4075);
PAINT GREEN (-2850 4075);
DISPLAY INVISIBLE (-2850 4075);
FORCEPROP 1 LAST NEEDS_NO_SIZE TRUE
J 0
(-2850 4074);
DISPLAY 0.468085 (-2850 4074);
PAINT GREEN (-2850 4074);
DISPLAY INVISIBLE (-2850 4074);
FORCEPROP 1 LAST CDS_LMAN_SYM_OUTLINE -150,150,150,-150
J 0
(-2850 4075);
DISPLAY 0.468085 (-2850 4075);
PAINT GREEN (-2850 4075);
DISPLAY INVISIBLE (-2850 4075);
FORCEPROP 2 LAST CDS_LIB pure_quanta
J 0
(-2850 4075);
DISPLAY INVISIBLE (-2850 4075);
FORCEPROP 0 LAST $SEC 1
J 0
(-2675 4200);
DISPLAY INVISIBLE (-2675 4200);
FORCEPROP 0 LAST CDS_SEC 1
J 0
(-2675 4200);
DISPLAY INVISIBLE (-2675 4200);
FORCEADD Q_LED..1
R 2
(-1775 4350);
FORCEPROP 1 LAST PART_NUMBER BEBL0172Z00
J 0
(-1875 4125);
DISPLAY 0.574468 (-1875 4125);
PAINT GREEN (-1875 4125);
DISPLAY INVISIBLE (-1875 4125);
FORCEPROP 0 LAST PACK_TYPE SMLF
J 0
(-1875 4175);
DISPLAY 0.638298 (-1875 4175);
FORCEPROP 2 LAST COLOR LED_BLUE
J 0
(-1875 4225);
DISPLAY 0.638298 (-1875 4225);
FORCEPROP 1 LAST MATERIAL IC
J 0
(-1750 4175);
DISPLAY 0.723404 (-1750 4175);
PAINT GREEN (-1750 4175);
FORCEPROP 2 LAST MANUF_PN LTST-C281TBKT-5A
J 0
(-1875 4075);
DISPLAY 0.638298 (-1875 4075);
FORCEPROP 1 LAST LOCATION D80
J 0
(-1875 4275);
DISPLAY 0.723404 (-1875 4275);
PAINT GREEN (-1875 4275);
FORCEPROP 0 LASTPIN (-1625 4350) $PN A
J 0
(-1615 4360);
DISPLAY 0.808511 (-1615 4360);
FORCEPROP 0 LASTPIN (-1925 4350) $PN C
J 2
(-1935 4360);
DISPLAY 0.808511 (-1935 4360);
FORCEPROP 1 LAST PATH I19
J 2
(-1900 4430);
DISPLAY 0.723404 (-1900 4430);
PAINT GREEN (-1900 4430);
DISPLAY INVISIBLE (-1900 4430);
FORCEPROP 2 LAST CDS_LIB pure_quanta
J 0
(-1775 4350);
DISPLAY INVISIBLE (-1775 4350);
FORCEPROP 1 LAST NEEDS_NO_SIZE TRUE
J 2
(-1753 4372);
DISPLAY 0.468085 (-1753 4372);
PAINT GREEN (-1753 4372);
DISPLAY INVISIBLE (-1753 4372);
FORCEPROP 0 LAST $SEC 1
J 0
(-1875 4325);
DISPLAY INVISIBLE (-1875 4325);
FORCEPROP 0 LAST CDS_SEC 1
J 0
(-1875 4325);
DISPLAY INVISIBLE (-1875 4325);
FORCEADD OFFPAGE..1
(-3950 1475);
PAINT AQUA (-3950 1475);
FORCEPROP 2 LAST $XR1 214 
J 0
(-4202 1439);
DISPLAY 0.638298 (-4202 1439);
PAINT MONO (-4202 1439);
FORCEPROP 2 LAST $XR0 292 
J 0
(-4202 1475);
DISPLAY 0.638298 (-4202 1475);
PAINT MONO (-4202 1475);
FORCEPROP 2 LAST PATH I2
J 0
(-4200 1550);
DISPLAY 1.021277 (-4200 1550);
DISPLAY INVISIBLE (-4200 1550);
FORCEPROP 1 LAST COMMENT_BODY TRUE
J 0
(-3825 1375);
DISPLAY 0.872340 (-3825 1375);
PAINT GREEN (-3825 1375);
DISPLAY INVISIBLE (-3825 1375);
FORCEPROP 1 LAST OFFPAGE TRUE
J 0
(-3625 1350);
DISPLAY 0.872340 (-3625 1350);
PAINT AQUA (-3625 1350);
DISPLAY INVISIBLE (-3625 1350);
FORCEPROP 2 LAST CDS_LIB standard
J 0
(-3950 1475);
DISPLAY INVISIBLE (-3950 1475);
FORCEADD Q_RES..1
(-425 4350);
FORCEPROP 1 LAST PART_NUMBER CS11302FB03
J 0
(-650 4450);
DISPLAY 0.638298 (-650 4450);
DISPLAY INVISIBLE (-650 4450);
FORCEPROP 1 LAST VALUE 130
J 2
(-225 4350);
DISPLAY 0.638298 (-225 4350);
FORCEPROP 1 LAST TOLERANCE 1%
J 0
(-200 4350);
DISPLAY 0.638298 (-200 4350);
FORCEPROP 1 LAST MATERIAL CHIP
J 0
(-575 4300);
DISPLAY 0.638298 (-575 4300);
FORCEPROP 1 LAST WATTAGE 1/16W
J 2
(-275 4300);
DISPLAY 0.638298 (-275 4300);
FORCEPROP 1 LAST PACK_TYPE 0402LF
J 0
(-125 4350);
DISPLAY 0.638298 (-125 4350);
FORCEPROP 1 LAST $LOCATION R3093
J 0
(-475 4400);
DISPLAY 0.978723 (-475 4400);
FORCEPROP 1 LASTPIN (-525 4350) $PN 1
J 0
(-513 4362);
DISPLAY 0.787234 (-513 4362);
PAINT MONO (-513 4362);
FORCEPROP 1 LASTPIN (-325 4350) $PN 2
J 0
(-363 4362);
DISPLAY 0.787234 (-363 4362);
PAINT MONO (-363 4362);
FORCEPROP 1 LAST PATH I20
J 0
(-475 4500);
DISPLAY 0.978723 (-475 4500);
PAINT WHITE (-475 4500);
DISPLAY INVISIBLE (-475 4500);
FORCEPROP 2 LAST CDS_LIB pure_quanta
J 0
(-425 4350);
DISPLAY INVISIBLE (-425 4350);
FORCEPROP 0 LAST CDS_LOCATION R3093
J 0
(-475 4450);
DISPLAY 1.021277 (-475 4450);
DISPLAY INVISIBLE (-475 4450);
FORCEPROP 0 LAST $SEC 1
J 0
(-475 4450);
DISPLAY 0.680851 (-475 4450);
PAINT MONO (-475 4450);
DISPLAY INVISIBLE (-475 4450);
FORCEPROP 0 LAST CDS_SEC 1
J 0
(-475 4450);
DISPLAY 1.021277 (-475 4450);
DISPLAY INVISIBLE (-475 4450);
FORCEADD UNIVERSAL_POWER..1
(200 625);
FORCEPROP 3 LASTPIN (200 575) SIG_NAME P3V3_AUX\g
J 0
(210 585);
DISPLAY 0.659574 (210 585);
PAINT MONO (210 585);
DISPLAY INVISIBLE (210 585);
FORCEPROP 1 LAST HDL_POWER P3V3_AUX
J 1
(200 675);
DISPLAY 0.723404 (200 675);
PAINT GREEN (200 675);
FORCEPROP 1 LAST PATH I21
J 0
(250 650);
DISPLAY 0.872340 (250 650);
PAINT AQUA (250 650);
DISPLAY INVISIBLE (250 650);
FORCEPROP 2 LAST CDS_LIB logical_power
J 0
(200 625);
DISPLAY INVISIBLE (200 625);
FORCEADD OFFPAGE..1
(825 1450);
PAINT AQUA (825 1450);
FORCEPROP 2 LAST $XR1 284 
J 0
(423 1450);
DISPLAY 0.638298 (423 1450);
PAINT MONO (423 1450);
FORCEPROP 2 LAST $XR0 214 
J 0
(543 1450);
DISPLAY 0.638298 (543 1450);
PAINT MONO (543 1450);
FORCEPROP 2 LAST PATH I22
J 0
(550 1500);
DISPLAY 1.021277 (550 1500);
DISPLAY INVISIBLE (550 1500);
FORCEPROP 1 LAST COMMENT_BODY TRUE
J 0
(950 1350);
DISPLAY 0.872340 (950 1350);
PAINT GREEN (950 1350);
DISPLAY INVISIBLE (950 1350);
FORCEPROP 1 LAST OFFPAGE TRUE
J 0
(1150 1325);
DISPLAY 0.872340 (1150 1325);
PAINT AQUA (1150 1325);
DISPLAY INVISIBLE (1150 1325);
FORCEPROP 2 LAST CDS_LIB standard
J 0
(825 1450);
DISPLAY INVISIBLE (825 1450);
FORCEADD UNIVERSAL_POWER..1
(250 1975);
FORCEPROP 3 LASTPIN (250 1925) SIG_NAME P3V3_AUX\g
J 0
(260 1935);
DISPLAY 0.659574 (260 1935);
PAINT MONO (260 1935);
DISPLAY INVISIBLE (260 1935);
FORCEPROP 1 LAST HDL_POWER P3V3_AUX
J 1
(250 2025);
DISPLAY 0.723404 (250 2025);
PAINT GREEN (250 2025);
FORCEPROP 1 LAST PATH I24
J 0
(300 2000);
DISPLAY 0.872340 (300 2000);
PAINT AQUA (300 2000);
DISPLAY INVISIBLE (300 2000);
FORCEPROP 2 LAST CDS_LIB logical_power
J 0
(250 1975);
DISPLAY INVISIBLE (250 1975);
FORCEADD OFFPAGE..1
(825 2700);
PAINT AQUA (825 2700);
FORCEPROP 2 LAST $XR1 213 
J 0
(423 2700);
DISPLAY 0.638298 (423 2700);
PAINT MONO (423 2700);
FORCEPROP 2 LAST $XR0 300 
J 0
(543 2700);
DISPLAY 0.638298 (543 2700);
PAINT MONO (543 2700);
FORCEPROP 2 LAST PATH I25
J 0
(550 2750);
DISPLAY 1.021277 (550 2750);
DISPLAY INVISIBLE (550 2750);
FORCEPROP 1 LAST COMMENT_BODY TRUE
J 0
(950 2600);
DISPLAY 0.872340 (950 2600);
PAINT GREEN (950 2600);
DISPLAY INVISIBLE (950 2600);
FORCEPROP 1 LAST OFFPAGE TRUE
J 0
(1150 2575);
DISPLAY 0.872340 (1150 2575);
PAINT AQUA (1150 2575);
DISPLAY INVISIBLE (1150 2575);
FORCEPROP 2 LAST CDS_LIB standard
J 0
(825 2700);
DISPLAY INVISIBLE (825 2700);
FORCEADD UNIVERSAL_POWER..1
(200 3150);
FORCEPROP 3 LASTPIN (200 3100) SIG_NAME P3V3_AUX\g
J 0
(210 3110);
DISPLAY 0.659574 (210 3110);
PAINT MONO (210 3110);
DISPLAY INVISIBLE (210 3110);
FORCEPROP 1 LAST HDL_POWER P3V3_AUX
J 1
(200 3200);
DISPLAY 0.723404 (200 3200);
PAINT GREEN (200 3200);
FORCEPROP 1 LAST PATH I26
J 0
(250 3175);
DISPLAY 0.872340 (250 3175);
PAINT AQUA (250 3175);
DISPLAY INVISIBLE (250 3175);
FORCEPROP 2 LAST CDS_LIB logical_power
J 0
(200 3150);
DISPLAY INVISIBLE (200 3150);
FORCEADD MOSFET_NCH_DUAL..2
(1925 2750);
FORCEPROP 1 LAST PART_NUMBER BAM138K0003
J 0
(2076 2656);
DISPLAY 0.723404 (2076 2656);
PAINT BLUE (2076 2656);
DISPLAY INVISIBLE (2076 2656);
FORCEPROP 2 LAST VALUE PJT138K
J 0
(2100 2775);
DISPLAY 0.723404 (2100 2775);
PAINT SKYBLUE (2100 2775);
FORCEPROP 1 LAST MATERIAL IC
J 0
(2076 2601);
DISPLAY 0.723404 (2076 2601);
PAINT SKYBLUE (2076 2601);
FORCEPROP 2 LAST PART_TYPE SMLF
J 0
(2100 2825);
DISPLAY 1.021277 (2100 2825);
FORCEPROP 1 LAST LOCATION Q86
J 0
(2076 2726);
DISPLAY 0.723404 (2076 2726);
PAINT AQUA (2076 2726);
FORCEPROP 2 LASTPIN (1975 2950) $PN 3
R 1
J 0
(1965 2960);
DISPLAY 0.723404 (1965 2960);
PAINT MONO (1965 2960);
FORCEPROP 2 LASTPIN (1725 2700) $PN 5
J 2
(1715 2710);
DISPLAY 0.723404 (1715 2710);
PAINT MONO (1715 2710);
FORCEPROP 2 LASTPIN (1975 2550) $PN 4
R 1
J 2
(1965 2540);
DISPLAY 0.723404 (1965 2540);
PAINT MONO (1965 2540);
FORCEPROP 1 LAST CDS_LMAN_SYM_OUTLINE -150,150,150,-150
J 0
(1925 2750);
DISPLAY 0.468085 (1925 2750);
PAINT GREEN (1925 2750);
DISPLAY INVISIBLE (1925 2750);
FORCEPROP 2 LAST CDS_LIB pure_quanta
J 0
(1925 2750);
DISPLAY INVISIBLE (1925 2750);
FORCEPROP 2 LAST SEC_TYPE 
J 0
(2100 2875);
DISPLAY 1.021277 (2100 2875);
DISPLAY INVISIBLE (2100 2875);
FORCEPROP 1 LAST PATH I27
J 0
(2075 2600);
DISPLAY 0.723404 (2075 2600);
PAINT GREEN (2075 2600);
DISPLAY INVISIBLE (2075 2600);
FORCEPROP 1 LAST NEEDS_NO_SIZE TRUE
J 0
(2075 2641);
DISPLAY 0.468085 (2075 2641);
PAINT GREEN (2075 2641);
DISPLAY INVISIBLE (2075 2641);
FORCEPROP 2 LAST SEC 2
J 0
(2100 2875);
DISPLAY 0.680851 (2100 2875);
PAINT MONO (2100 2875);
DISPLAY INVISIBLE (2100 2875);
FORCEADD UNIVERSAL_GND..1
(1975 1150);
FORCEPROP 3 LASTPIN (1975 1200) SIG_NAME GND\g
J 0
(1985 1210);
DISPLAY 0.659574 (1985 1210);
PAINT MONO (1985 1210);
DISPLAY INVISIBLE (1985 1210);
FORCEPROP 1 LAST PATH I28
J 0
(2050 1150);
DISPLAY 0.872340 (2050 1150);
PAINT AQUA (2050 1150);
DISPLAY INVISIBLE (2050 1150);
FORCEPROP 1 LAST HDL_POWER GND
J 1
(2000 1075);
DISPLAY 0.872340 (2000 1075);
PAINT GREEN (2000 1075);
DISPLAY INVISIBLE (2000 1075);
FORCEPROP 2 LAST CDS_LIB logical_power
J 0
(1975 1150);
DISPLAY INVISIBLE (1975 1150);
FORCEADD UNIVERSAL_GND..1
(1975 2400);
FORCEPROP 3 LASTPIN (1975 2450) SIG_NAME GND\g
J 0
(1985 2460);
DISPLAY 0.659574 (1985 2460);
PAINT MONO (1985 2460);
DISPLAY INVISIBLE (1985 2460);
FORCEPROP 1 LAST PATH I29
J 0
(2050 2400);
DISPLAY 0.872340 (2050 2400);
PAINT AQUA (2050 2400);
DISPLAY INVISIBLE (2050 2400);
FORCEPROP 1 LAST HDL_POWER GND
J 1
(2000 2325);
DISPLAY 0.872340 (2000 2325);
PAINT GREEN (2000 2325);
DISPLAY INVISIBLE (2000 2325);
FORCEPROP 2 LAST CDS_LIB logical_power
J 0
(1975 2400);
DISPLAY INVISIBLE (1975 2400);
FORCEADD MOSFET_NCH_DUAL..2
(-2850 200);
FORCEPROP 1 LAST PART_NUMBER BAM138K0003
J 0
(-2699 106);
DISPLAY 0.723404 (-2699 106);
PAINT BLUE (-2699 106);
DISPLAY INVISIBLE (-2699 106);
FORCEPROP 1 LAST MATERIAL IC
J 0
(-2699 51);
DISPLAY 0.723404 (-2699 51);
PAINT SKYBLUE (-2699 51);
FORCEPROP 2 LAST PART_TYPE SMLF
J 0
(-2675 275);
DISPLAY 1.021277 (-2675 275);
FORCEPROP 2 LAST VALUE PJT138K
J 0
(-2675 225);
DISPLAY 0.723404 (-2675 225);
PAINT SKYBLUE (-2675 225);
FORCEPROP 1 LAST LOCATION Q85
J 0
(-2699 176);
DISPLAY 0.723404 (-2699 176);
PAINT AQUA (-2699 176);
FORCEPROP 2 LASTPIN (-2800 400) $PN 3
R 1
J 0
(-2810 410);
DISPLAY 0.723404 (-2810 410);
PAINT MONO (-2810 410);
FORCEPROP 2 LASTPIN (-3050 150) $PN 5
J 2
(-3060 160);
DISPLAY 0.723404 (-3060 160);
PAINT MONO (-3060 160);
FORCEPROP 2 LASTPIN (-2800 0) $PN 4
R 1
J 2
(-2810 -10);
DISPLAY 0.723404 (-2810 -10);
PAINT MONO (-2810 -10);
FORCEPROP 1 LAST PATH I3
J 0
(-2700 50);
DISPLAY 0.723404 (-2700 50);
PAINT GREEN (-2700 50);
DISPLAY INVISIBLE (-2700 50);
FORCEPROP 2 LAST SEC_TYPE 
J 0
(-2675 325);
DISPLAY 1.021277 (-2675 325);
DISPLAY INVISIBLE (-2675 325);
FORCEPROP 2 LAST CDS_LIB pure_quanta
J 0
(-2850 200);
DISPLAY INVISIBLE (-2850 200);
FORCEPROP 1 LAST NEEDS_NO_SIZE TRUE
J 0
(-2700 91);
DISPLAY 0.468085 (-2700 91);
PAINT GREEN (-2700 91);
DISPLAY INVISIBLE (-2700 91);
FORCEPROP 1 LAST CDS_LMAN_SYM_OUTLINE -150,150,150,-150
J 0
(-2850 200);
DISPLAY 0.468085 (-2850 200);
PAINT GREEN (-2850 200);
DISPLAY INVISIBLE (-2850 200);
FORCEPROP 2 LAST SEC 2
J 0
(-2675 325);
DISPLAY 0.680851 (-2675 325);
PAINT MONO (-2675 325);
DISPLAY INVISIBLE (-2675 325);
FORCEADD Q_LED..1
R 2
(3000 1775);
FORCEPROP 1 LAST PART_NUMBER BEBL0172Z00
J 0
(2900 1550);
DISPLAY 0.574468 (2900 1550);
PAINT GREEN (2900 1550);
DISPLAY INVISIBLE (2900 1550);
FORCEPROP 1 LAST MATERIAL IC
J 0
(3025 1600);
DISPLAY 0.723404 (3025 1600);
PAINT GREEN (3025 1600);
FORCEPROP 2 LAST COLOR LED_BLUE
J 0
(2900 1650);
DISPLAY 0.638298 (2900 1650);
FORCEPROP 0 LAST PACK_TYPE SMLF
J 0
(2900 1600);
DISPLAY 0.638298 (2900 1600);
FORCEPROP 2 LAST MANUF_PN LTST-C281TBKT-5A
J 0
(2900 1500);
DISPLAY 0.638298 (2900 1500);
FORCEPROP 1 LAST LOCATION D86
J 0
(2900 1700);
DISPLAY 0.723404 (2900 1700);
PAINT GREEN (2900 1700);
FORCEPROP 0 LASTPIN (3150 1775) $PN A
J 0
(3160 1785);
DISPLAY 0.808511 (3160 1785);
FORCEPROP 0 LASTPIN (2850 1775) $PN C
J 2
(2840 1785);
DISPLAY 0.808511 (2840 1785);
FORCEPROP 1 LAST PATH I30
J 2
(2875 1855);
DISPLAY 0.723404 (2875 1855);
PAINT GREEN (2875 1855);
DISPLAY INVISIBLE (2875 1855);
FORCEPROP 2 LAST CDS_LIB pure_quanta
J 0
(3000 1775);
DISPLAY INVISIBLE (3000 1775);
FORCEPROP 1 LAST NEEDS_NO_SIZE TRUE
J 2
(3022 1797);
DISPLAY 0.468085 (3022 1797);
PAINT GREEN (3022 1797);
DISPLAY INVISIBLE (3022 1797);
FORCEPROP 0 LAST $SEC 1
J 0
(2900 1750);
DISPLAY INVISIBLE (2900 1750);
FORCEPROP 0 LAST CDS_SEC 1
J 0
(2900 1750);
DISPLAY INVISIBLE (2900 1750);
FORCEADD UNIVERSAL_GND..1
(1975 3725);
FORCEPROP 3 LASTPIN (1975 3775) SIG_NAME GND\g
J 0
(1985 3785);
DISPLAY 0.659574 (1985 3785);
PAINT MONO (1985 3785);
DISPLAY INVISIBLE (1985 3785);
FORCEPROP 1 LAST PATH I31
J 0
(2050 3725);
DISPLAY 0.872340 (2050 3725);
PAINT AQUA (2050 3725);
DISPLAY INVISIBLE (2050 3725);
FORCEPROP 1 LAST HDL_POWER GND
J 1
(2000 3650);
DISPLAY 0.872340 (2000 3650);
PAINT GREEN (2000 3650);
DISPLAY INVISIBLE (2000 3650);
FORCEPROP 2 LAST CDS_LIB logical_power
J 0
(1975 3725);
DISPLAY INVISIBLE (1975 3725);
FORCEADD Q_LED..1
R 2
(3000 3025);
FORCEPROP 1 LAST PART_NUMBER BEBL0172Z00
J 0
(2900 2800);
DISPLAY 0.574468 (2900 2800);
PAINT GREEN (2900 2800);
DISPLAY INVISIBLE (2900 2800);
FORCEPROP 1 LAST MATERIAL IC
J 0
(3025 2850);
DISPLAY 0.723404 (3025 2850);
PAINT GREEN (3025 2850);
FORCEPROP 0 LAST PACK_TYPE SMLF
J 0
(2900 2850);
DISPLAY 0.638298 (2900 2850);
FORCEPROP 2 LAST COLOR LED_BLUE
J 0
(2900 2900);
DISPLAY 0.638298 (2900 2900);
FORCEPROP 2 LAST MANUF_PN LTST-C281TBKT-5A
J 0
(2900 2750);
DISPLAY 0.638298 (2900 2750);
FORCEPROP 1 LAST LOCATION D85
J 0
(2900 2950);
DISPLAY 0.723404 (2900 2950);
PAINT GREEN (2900 2950);
FORCEPROP 0 LASTPIN (3150 3025) $PN A
J 0
(3160 3035);
DISPLAY 0.808511 (3160 3035);
FORCEPROP 0 LASTPIN (2850 3025) $PN C
J 2
(2840 3035);
DISPLAY 0.808511 (2840 3035);
FORCEPROP 1 LAST PATH I32
J 2
(2875 3105);
DISPLAY 0.723404 (2875 3105);
PAINT GREEN (2875 3105);
DISPLAY INVISIBLE (2875 3105);
FORCEPROP 2 LAST CDS_LIB pure_quanta
J 0
(3000 3025);
DISPLAY INVISIBLE (3000 3025);
FORCEPROP 1 LAST NEEDS_NO_SIZE TRUE
J 2
(3022 3047);
DISPLAY 0.468085 (3022 3047);
PAINT GREEN (3022 3047);
DISPLAY INVISIBLE (3022 3047);
FORCEPROP 0 LAST $SEC 1
J 0
(2900 3000);
DISPLAY INVISIBLE (2900 3000);
FORCEPROP 0 LAST CDS_SEC 1
J 0
(2900 3000);
DISPLAY INVISIBLE (2900 3000);
FORCEADD UNIVERSAL_POWER..1
(225 4500);
FORCEPROP 3 LASTPIN (225 4450) SIG_NAME P3V3_AUX\g
J 0
(235 4460);
DISPLAY 0.659574 (235 4460);
PAINT MONO (235 4460);
DISPLAY INVISIBLE (235 4460);
FORCEPROP 1 LAST HDL_POWER P3V3_AUX
J 1
(225 4550);
DISPLAY 0.723404 (225 4550);
PAINT GREEN (225 4550);
FORCEPROP 1 LAST PATH I33
J 0
(275 4525);
DISPLAY 0.872340 (275 4525);
PAINT AQUA (275 4525);
DISPLAY INVISIBLE (275 4525);
FORCEPROP 2 LAST CDS_LIB logical_power
J 0
(225 4500);
DISPLAY INVISIBLE (225 4500);
FORCEADD OFFPAGE..1
(825 4025);
PAINT AQUA (825 4025);
FORCEPROP 2 LAST $XR1 214 
J 0
(423 4025);
DISPLAY 0.638298 (423 4025);
PAINT MONO (423 4025);
FORCEPROP 2 LAST $XR0 292 
J 0
(543 4025);
DISPLAY 0.638298 (543 4025);
PAINT MONO (543 4025);
FORCEPROP 2 LAST PATH I34
J 0
(550 4075);
DISPLAY 1.021277 (550 4075);
DISPLAY INVISIBLE (550 4075);
FORCEPROP 1 LAST COMMENT_BODY TRUE
J 0
(950 3925);
DISPLAY 0.872340 (950 3925);
PAINT GREEN (950 3925);
DISPLAY INVISIBLE (950 3925);
FORCEPROP 1 LAST OFFPAGE TRUE
J 0
(1150 3900);
DISPLAY 0.872340 (1150 3900);
PAINT AQUA (1150 3900);
DISPLAY INVISIBLE (1150 3900);
FORCEPROP 2 LAST CDS_LIB standard
J 0
(825 4025);
DISPLAY INVISIBLE (825 4025);
FORCEADD MOSFET_NCH_DUAL..1
(1925 4075);
FORCEPROP 1 LAST PART_NUMBER BAM138K0003
J 0
(2076 3989);
DISPLAY 0.723404 (2076 3989);
PAINT GREEN (2076 3989);
DISPLAY INVISIBLE (2076 3989);
FORCEPROP 2 LAST VALUE PJT138K
J 0
(2100 4100);
DISPLAY 1.021277 (2100 4100);
FORCEPROP 2 LAST PART_TYPE SMLF
J 0
(2100 4150);
DISPLAY 1.021277 (2100 4150);
FORCEPROP 1 LAST MATERIAL IC
J 0
(2076 3924);
DISPLAY 0.723404 (2076 3924);
PAINT GREEN (2076 3924);
FORCEPROP 1 LAST LOCATION Q86
J 0
(2076 4049);
DISPLAY 0.723404 (2076 4049);
PAINT GREEN (2076 4049);
FORCEPROP 0 LASTPIN (1975 4275) $PN 6
R 1
J 0
(1965 4285);
DISPLAY 0.808511 (1965 4285);
FORCEPROP 0 LASTPIN (1725 4025) $PN 2
J 2
(1715 4035);
DISPLAY 0.808511 (1715 4035);
FORCEPROP 0 LASTPIN (1975 3875) $PN 1
R 1
J 2
(1965 3865);
DISPLAY 0.808511 (1965 3865);
FORCEPROP 1 LAST PATH I35
J 0
(1925 4075);
DISPLAY 0.723404 (1925 4075);
PAINT GREEN (1925 4075);
DISPLAY INVISIBLE (1925 4075);
FORCEPROP 1 LAST NEEDS_NO_SIZE TRUE
J 0
(1925 4074);
DISPLAY 0.468085 (1925 4074);
PAINT GREEN (1925 4074);
DISPLAY INVISIBLE (1925 4074);
FORCEPROP 1 LAST CDS_LMAN_SYM_OUTLINE -150,150,150,-150
J 0
(1925 4075);
DISPLAY 0.468085 (1925 4075);
PAINT GREEN (1925 4075);
DISPLAY INVISIBLE (1925 4075);
FORCEPROP 2 LAST CDS_LIB pure_quanta
J 0
(1925 4075);
DISPLAY INVISIBLE (1925 4075);
FORCEPROP 0 LAST $SEC 1
J 0
(2100 4200);
DISPLAY INVISIBLE (2100 4200);
FORCEPROP 0 LAST CDS_SEC 1
J 0
(2100 4200);
DISPLAY INVISIBLE (2100 4200);
FORCEADD Q_LED..1
R 2
(3000 4350);
FORCEPROP 1 LAST PART_NUMBER BEBL0172Z00
J 0
(2900 4125);
DISPLAY 0.574468 (2900 4125);
PAINT GREEN (2900 4125);
DISPLAY INVISIBLE (2900 4125);
FORCEPROP 2 LAST MANUF_PN LTST-C281TBKT-5A
J 0
(2900 4075);
DISPLAY 0.638298 (2900 4075);
FORCEPROP 2 LAST COLOR LED_BLUE
J 0
(2900 4225);
DISPLAY 0.638298 (2900 4225);
FORCEPROP 1 LAST MATERIAL IC
J 0
(3025 4175);
DISPLAY 0.723404 (3025 4175);
PAINT GREEN (3025 4175);
FORCEPROP 0 LAST PACK_TYPE SMLF
J 0
(2900 4175);
DISPLAY 0.638298 (2900 4175);
FORCEPROP 1 LAST LOCATION D84
J 0
(2900 4275);
DISPLAY 0.723404 (2900 4275);
PAINT GREEN (2900 4275);
FORCEPROP 0 LASTPIN (3150 4350) $PN A
J 0
(3160 4360);
DISPLAY 0.808511 (3160 4360);
FORCEPROP 0 LASTPIN (2850 4350) $PN C
J 2
(2840 4360);
DISPLAY 0.808511 (2840 4360);
FORCEPROP 1 LAST PATH I36
J 2
(2875 4430);
DISPLAY 0.723404 (2875 4430);
PAINT GREEN (2875 4430);
DISPLAY INVISIBLE (2875 4430);
FORCEPROP 1 LAST NEEDS_NO_SIZE TRUE
J 2
(3022 4372);
DISPLAY 0.468085 (3022 4372);
PAINT GREEN (3022 4372);
DISPLAY INVISIBLE (3022 4372);
FORCEPROP 2 LAST CDS_LIB pure_quanta
J 0
(3000 4350);
DISPLAY INVISIBLE (3000 4350);
FORCEPROP 0 LAST $SEC 1
J 0
(2900 4325);
DISPLAY INVISIBLE (2900 4325);
FORCEPROP 0 LAST CDS_SEC 1
J 0
(2900 4325);
DISPLAY INVISIBLE (2900 4325);
FORCEADD Q_RES..1
(4300 1775);
FORCEPROP 1 LAST PART_NUMBER CS11302FB03
J 0
(4075 1875);
DISPLAY 0.638298 (4075 1875);
DISPLAY INVISIBLE (4075 1875);
FORCEPROP 1 LAST VALUE 130
J 2
(4500 1775);
DISPLAY 0.638298 (4500 1775);
FORCEPROP 1 LAST TOLERANCE 1%
J 0
(4525 1775);
DISPLAY 0.638298 (4525 1775);
FORCEPROP 1 LAST MATERIAL CHIP
J 0
(4150 1725);
DISPLAY 0.638298 (4150 1725);
FORCEPROP 1 LAST WATTAGE 1/16W
J 2
(4450 1725);
DISPLAY 0.638298 (4450 1725);
FORCEPROP 1 LAST PACK_TYPE 0402LF
J 0
(4600 1775);
DISPLAY 0.638298 (4600 1775);
FORCEPROP 1 LAST $LOCATION R3098
J 0
(4250 1825);
DISPLAY 0.978723 (4250 1825);
FORCEPROP 1 LASTPIN (4200 1775) $PN 1
J 0
(4212 1787);
DISPLAY 0.787234 (4212 1787);
PAINT MONO (4212 1787);
FORCEPROP 1 LASTPIN (4400 1775) $PN 2
J 0
(4362 1787);
DISPLAY 0.787234 (4362 1787);
PAINT MONO (4362 1787);
FORCEPROP 1 LAST PATH I37
J 0
(4250 1925);
DISPLAY 0.978723 (4250 1925);
PAINT WHITE (4250 1925);
DISPLAY INVISIBLE (4250 1925);
FORCEPROP 2 LAST CDS_LIB pure_quanta
J 0
(4300 1775);
DISPLAY INVISIBLE (4300 1775);
FORCEPROP 0 LAST CDS_LOCATION R3098
J 0
(4250 1875);
DISPLAY 1.021277 (4250 1875);
DISPLAY INVISIBLE (4250 1875);
FORCEPROP 0 LAST $SEC 1
J 0
(4250 1875);
DISPLAY 0.680851 (4250 1875);
PAINT MONO (4250 1875);
DISPLAY INVISIBLE (4250 1875);
FORCEPROP 0 LAST CDS_SEC 1
J 0
(4250 1875);
DISPLAY 1.021277 (4250 1875);
DISPLAY INVISIBLE (4250 1875);
FORCEADD Q_RES..1
(4300 3025);
FORCEPROP 1 LAST PART_NUMBER CS11302FB03
J 0
(4075 3125);
DISPLAY 0.638298 (4075 3125);
DISPLAY INVISIBLE (4075 3125);
FORCEPROP 1 LAST VALUE 130
J 2
(4500 3025);
DISPLAY 0.638298 (4500 3025);
FORCEPROP 1 LAST TOLERANCE 1%
J 0
(4525 3025);
DISPLAY 0.638298 (4525 3025);
FORCEPROP 1 LAST MATERIAL CHIP
J 0
(4150 2975);
DISPLAY 0.638298 (4150 2975);
FORCEPROP 1 LAST WATTAGE 1/16W
J 2
(4450 2975);
DISPLAY 0.638298 (4450 2975);
FORCEPROP 1 LAST PACK_TYPE 0402LF
J 0
(4600 3025);
DISPLAY 0.638298 (4600 3025);
FORCEPROP 1 LAST $LOCATION R3097
J 0
(4250 3075);
DISPLAY 0.978723 (4250 3075);
FORCEPROP 1 LASTPIN (4200 3025) $PN 1
J 0
(4212 3037);
DISPLAY 0.787234 (4212 3037);
PAINT MONO (4212 3037);
FORCEPROP 1 LASTPIN (4400 3025) $PN 2
J 0
(4362 3037);
DISPLAY 0.787234 (4362 3037);
PAINT MONO (4362 3037);
FORCEPROP 1 LAST PATH I38
J 0
(4250 3175);
DISPLAY 0.978723 (4250 3175);
PAINT WHITE (4250 3175);
DISPLAY INVISIBLE (4250 3175);
FORCEPROP 2 LAST CDS_LIB pure_quanta
J 0
(4300 3025);
DISPLAY INVISIBLE (4300 3025);
FORCEPROP 0 LAST CDS_LOCATION R3097
J 0
(4250 3125);
DISPLAY 1.021277 (4250 3125);
DISPLAY INVISIBLE (4250 3125);
FORCEPROP 0 LAST $SEC 1
J 0
(4250 3125);
DISPLAY 0.680851 (4250 3125);
PAINT MONO (4250 3125);
DISPLAY INVISIBLE (4250 3125);
FORCEPROP 0 LAST CDS_SEC 1
J 0
(4250 3125);
DISPLAY 1.021277 (4250 3125);
DISPLAY INVISIBLE (4250 3125);
FORCEADD UNIVERSAL_POWER..1
(4975 1925);
FORCEPROP 3 LASTPIN (4975 1875) SIG_NAME P3V3_AUX\g
J 0
(4985 1885);
DISPLAY 0.659574 (4985 1885);
PAINT MONO (4985 1885);
DISPLAY INVISIBLE (4985 1885);
FORCEPROP 1 LAST HDL_POWER P3V3_AUX
J 1
(4975 1975);
DISPLAY 0.723404 (4975 1975);
PAINT GREEN (4975 1975);
FORCEPROP 1 LAST PATH I39
J 0
(5025 1950);
DISPLAY 0.872340 (5025 1950);
PAINT AQUA (5025 1950);
DISPLAY INVISIBLE (5025 1950);
FORCEPROP 2 LAST CDS_LIB logical_power
J 0
(4975 1925);
DISPLAY INVISIBLE (4975 1925);
FORCEADD UNIVERSAL_GND..1
(-2800 -150);
FORCEPROP 3 LASTPIN (-2800 -100) SIG_NAME GND\g
J 0
(-2790 -90);
DISPLAY 0.659574 (-2790 -90);
PAINT MONO (-2790 -90);
DISPLAY INVISIBLE (-2790 -90);
FORCEPROP 1 LAST PATH I4
J 0
(-2725 -150);
DISPLAY 0.872340 (-2725 -150);
PAINT AQUA (-2725 -150);
DISPLAY INVISIBLE (-2725 -150);
FORCEPROP 1 LAST HDL_POWER GND
J 1
(-2775 -225);
DISPLAY 0.872340 (-2775 -225);
PAINT GREEN (-2775 -225);
DISPLAY INVISIBLE (-2775 -225);
FORCEPROP 2 LAST CDS_LIB logical_power
J 0
(-2800 -150);
DISPLAY INVISIBLE (-2800 -150);
FORCEADD UNIVERSAL_POWER..1
(4950 3175);
FORCEPROP 3 LASTPIN (4950 3125) SIG_NAME P3V3_AUX\g
J 0
(4960 3135);
DISPLAY 0.659574 (4960 3135);
PAINT MONO (4960 3135);
DISPLAY INVISIBLE (4960 3135);
FORCEPROP 1 LAST HDL_POWER P3V3_AUX
J 1
(4950 3225);
DISPLAY 0.723404 (4950 3225);
PAINT GREEN (4950 3225);
FORCEPROP 1 LAST PATH I40
J 0
(5000 3200);
DISPLAY 0.872340 (5000 3200);
PAINT AQUA (5000 3200);
DISPLAY INVISIBLE (5000 3200);
FORCEPROP 2 LAST CDS_LIB logical_power
J 0
(4950 3175);
DISPLAY INVISIBLE (4950 3175);
FORCEADD Q_RES..1
(4325 4350);
FORCEPROP 1 LAST PART_NUMBER CS11302FB03
J 0
(4100 4450);
DISPLAY 0.638298 (4100 4450);
DISPLAY INVISIBLE (4100 4450);
FORCEPROP 1 LAST VALUE 130
J 2
(4525 4350);
DISPLAY 0.638298 (4525 4350);
FORCEPROP 1 LAST TOLERANCE 1%
J 0
(4550 4350);
DISPLAY 0.638298 (4550 4350);
FORCEPROP 1 LAST MATERIAL CHIP
J 0
(4175 4300);
DISPLAY 0.638298 (4175 4300);
FORCEPROP 1 LAST WATTAGE 1/16W
J 2
(4475 4300);
DISPLAY 0.638298 (4475 4300);
FORCEPROP 1 LAST PACK_TYPE 0402LF
J 0
(4625 4350);
DISPLAY 0.638298 (4625 4350);
FORCEPROP 1 LAST $LOCATION R3099
J 0
(4275 4400);
DISPLAY 0.978723 (4275 4400);
FORCEPROP 1 LASTPIN (4225 4350) $PN 1
J 0
(4237 4362);
DISPLAY 0.787234 (4237 4362);
PAINT MONO (4237 4362);
FORCEPROP 1 LASTPIN (4425 4350) $PN 2
J 0
(4387 4362);
DISPLAY 0.787234 (4387 4362);
PAINT MONO (4387 4362);
FORCEPROP 1 LAST PATH I41
J 0
(4275 4500);
DISPLAY 0.978723 (4275 4500);
PAINT WHITE (4275 4500);
DISPLAY INVISIBLE (4275 4500);
FORCEPROP 2 LAST CDS_LIB pure_quanta
J 0
(4325 4350);
DISPLAY INVISIBLE (4325 4350);
FORCEPROP 0 LAST CDS_LOCATION R3099
J 0
(4275 4450);
DISPLAY 1.021277 (4275 4450);
DISPLAY INVISIBLE (4275 4450);
FORCEPROP 0 LAST $SEC 1
J 0
(4275 4450);
DISPLAY 0.680851 (4275 4450);
PAINT MONO (4275 4450);
DISPLAY INVISIBLE (4275 4450);
FORCEPROP 0 LAST CDS_SEC 1
J 0
(4275 4450);
DISPLAY 1.021277 (4275 4450);
DISPLAY INVISIBLE (4275 4450);
FORCEADD UNIVERSAL_POWER..1
(4925 4525);
FORCEPROP 3 LASTPIN (4925 4475) SIG_NAME P3V3_AUX\g
J 0
(4935 4485);
DISPLAY 0.659574 (4935 4485);
PAINT MONO (4935 4485);
DISPLAY INVISIBLE (4935 4485);
FORCEPROP 1 LAST HDL_POWER P3V3_AUX
J 1
(4925 4575);
DISPLAY 0.723404 (4925 4575);
PAINT GREEN (4925 4575);
FORCEPROP 1 LAST PATH I42
J 0
(4975 4550);
DISPLAY 0.872340 (4975 4550);
PAINT AQUA (4975 4550);
DISPLAY INVISIBLE (4975 4550);
FORCEPROP 2 LAST CDS_LIB logical_power
J 0
(4925 4525);
DISPLAY INVISIBLE (4925 4525);
FORCEADD MOSFET_NCH_DUAL..2
(1925 1500);
FORCEPROP 1 LAST PART_NUMBER BAM138K0003
J 0
(2076 1406);
DISPLAY 0.723404 (2076 1406);
PAINT BLUE (2076 1406);
DISPLAY INVISIBLE (2076 1406);
FORCEPROP 2 LAST PART_TYPE SMLF
J 0
(2100 1575);
DISPLAY 1.021277 (2100 1575);
FORCEPROP 1 LAST MATERIAL IC
J 0
(2076 1351);
DISPLAY 0.723404 (2076 1351);
PAINT SKYBLUE (2076 1351);
FORCEPROP 2 LAST VALUE PJT138K
J 0
(2100 1525);
DISPLAY 0.723404 (2100 1525);
PAINT SKYBLUE (2100 1525);
FORCEPROP 1 LAST LOCATION Q83
J 0
(2076 1476);
DISPLAY 0.723404 (2076 1476);
PAINT GREEN (2076 1476);
FORCEPROP 0 LASTPIN (1975 1700) $PN 3
R 1
J 0
(1965 1710);
DISPLAY 0.680851 (1965 1710);
PAINT MONO (1965 1710);
FORCEPROP 0 LASTPIN (1725 1450) $PN 5
J 2
(1715 1460);
DISPLAY 0.680851 (1715 1460);
PAINT MONO (1715 1460);
FORCEPROP 0 LASTPIN (1975 1300) $PN 4
R 1
J 2
(1965 1290);
DISPLAY 0.680851 (1965 1290);
PAINT MONO (1965 1290);
FORCEPROP 1 LAST NEEDS_NO_SIZE TRUE
J 0
(2075 1391);
DISPLAY 0.468085 (2075 1391);
PAINT GREEN (2075 1391);
DISPLAY INVISIBLE (2075 1391);
FORCEPROP 1 LAST CDS_LMAN_SYM_OUTLINE -150,150,150,-150
J 0
(1925 1500);
DISPLAY 0.468085 (1925 1500);
PAINT GREEN (1925 1500);
DISPLAY INVISIBLE (1925 1500);
FORCEPROP 1 LAST PATH I43
J 0
(2075 1350);
DISPLAY 0.723404 (2075 1350);
PAINT GREEN (2075 1350);
DISPLAY INVISIBLE (2075 1350);
FORCEPROP 2 LAST CDS_LIB pure_quanta
J 0
(1925 1500);
DISPLAY INVISIBLE (1925 1500);
FORCEPROP 0 LAST $SEC 2
J 0
(2100 1625);
DISPLAY 0.680851 (2100 1625);
PAINT MONO (2100 1625);
DISPLAY INVISIBLE (2100 1625);
FORCEPROP 0 LAST CDS_SEC 2
J 0
(2100 1625);
DISPLAY 1.021277 (2100 1625);
DISPLAY INVISIBLE (2100 1625);
FORCEADD UNIVERSAL_GND..1
(-2800 1175);
FORCEPROP 3 LASTPIN (-2800 1225) SIG_NAME GND\g
J 0
(-2790 1235);
DISPLAY 0.659574 (-2790 1235);
PAINT MONO (-2790 1235);
DISPLAY INVISIBLE (-2790 1235);
FORCEPROP 1 LAST PATH I5
J 0
(-2725 1175);
DISPLAY 0.872340 (-2725 1175);
PAINT AQUA (-2725 1175);
DISPLAY INVISIBLE (-2725 1175);
FORCEPROP 1 LAST HDL_POWER GND
J 1
(-2775 1100);
DISPLAY 0.872340 (-2775 1100);
PAINT GREEN (-2775 1100);
DISPLAY INVISIBLE (-2775 1100);
FORCEPROP 2 LAST CDS_LIB logical_power
J 0
(-2800 1175);
DISPLAY INVISIBLE (-2800 1175);
FORCEADD MOSFET_NCH_DUAL..1
(-2850 1525);
FORCEPROP 1 LAST PART_NUMBER BAM138K0003
J 0
(-2699 1439);
DISPLAY 0.723404 (-2699 1439);
PAINT GREEN (-2699 1439);
DISPLAY INVISIBLE (-2699 1439);
FORCEPROP 1 LAST MATERIAL IC
J 0
(-2699 1374);
DISPLAY 0.723404 (-2699 1374);
PAINT GREEN (-2699 1374);
FORCEPROP 2 LAST PART_TYPE SMLF
J 0
(-2675 1600);
DISPLAY 1.021277 (-2675 1600);
FORCEPROP 2 LAST VALUE PJT138K
J 0
(-2675 1550);
DISPLAY 1.021277 (-2675 1550);
FORCEPROP 1 LAST LOCATION Q85
J 0
(-2699 1499);
DISPLAY 0.723404 (-2699 1499);
PAINT GREEN (-2699 1499);
FORCEPROP 0 LASTPIN (-2800 1725) $PN 6
R 1
J 0
(-2810 1735);
DISPLAY 0.808511 (-2810 1735);
FORCEPROP 0 LASTPIN (-3050 1475) $PN 2
J 2
(-3060 1485);
DISPLAY 0.808511 (-3060 1485);
FORCEPROP 0 LASTPIN (-2800 1325) $PN 1
R 1
J 2
(-2810 1315);
DISPLAY 0.808511 (-2810 1315);
FORCEPROP 1 LAST PATH I6
J 0
(-2850 1525);
DISPLAY 0.723404 (-2850 1525);
PAINT GREEN (-2850 1525);
DISPLAY INVISIBLE (-2850 1525);
FORCEPROP 1 LAST NEEDS_NO_SIZE TRUE
J 0
(-2850 1524);
DISPLAY 0.468085 (-2850 1524);
PAINT GREEN (-2850 1524);
DISPLAY INVISIBLE (-2850 1524);
FORCEPROP 1 LAST CDS_LMAN_SYM_OUTLINE -150,150,150,-150
J 0
(-2850 1525);
DISPLAY 0.468085 (-2850 1525);
PAINT GREEN (-2850 1525);
DISPLAY INVISIBLE (-2850 1525);
FORCEPROP 2 LAST CDS_LIB pure_quanta
J 0
(-2850 1525);
DISPLAY INVISIBLE (-2850 1525);
FORCEPROP 0 LAST $SEC 1
J 0
(-2675 1650);
DISPLAY INVISIBLE (-2675 1650);
FORCEPROP 0 LAST CDS_SEC 1
J 0
(-2675 1650);
DISPLAY INVISIBLE (-2675 1650);
FORCEADD OFFPAGE..1
(-3950 2700);
PAINT AQUA (-3950 2700);
FORCEPROP 2 LAST $XR1 213 
J 0
(-4202 2664);
DISPLAY 0.638298 (-4202 2664);
PAINT MONO (-4202 2664);
FORCEPROP 2 LAST $XR0 299 
J 0
(-4202 2700);
DISPLAY 0.638298 (-4202 2700);
PAINT MONO (-4202 2700);
FORCEPROP 2 LAST PATH I7
J 0
(-4200 2750);
DISPLAY 1.021277 (-4200 2750);
DISPLAY INVISIBLE (-4200 2750);
FORCEPROP 1 LAST COMMENT_BODY TRUE
J 0
(-3825 2600);
DISPLAY 0.872340 (-3825 2600);
PAINT GREEN (-3825 2600);
DISPLAY INVISIBLE (-3825 2600);
FORCEPROP 1 LAST OFFPAGE TRUE
J 0
(-3625 2575);
DISPLAY 0.872340 (-3625 2575);
PAINT AQUA (-3625 2575);
DISPLAY INVISIBLE (-3625 2575);
FORCEPROP 2 LAST CDS_LIB standard
J 0
(-3950 2700);
DISPLAY INVISIBLE (-3950 2700);
FORCEADD MOSFET_NCH_DUAL..2
(-2850 2750);
FORCEPROP 1 LAST PART_NUMBER BAM138K0003
J 0
(-2699 2656);
DISPLAY 0.723404 (-2699 2656);
PAINT BLUE (-2699 2656);
DISPLAY INVISIBLE (-2699 2656);
FORCEPROP 1 LAST MATERIAL IC
J 0
(-2699 2601);
DISPLAY 0.723404 (-2699 2601);
PAINT SKYBLUE (-2699 2601);
FORCEPROP 2 LAST VALUE PJT138K
J 0
(-2675 2775);
DISPLAY 0.723404 (-2675 2775);
PAINT SKYBLUE (-2675 2775);
FORCEPROP 2 LAST PART_TYPE SMLF
J 0
(-2675 2825);
DISPLAY 1.021277 (-2675 2825);
FORCEPROP 1 LAST LOCATION Q84
J 0
(-2699 2726);
DISPLAY 0.723404 (-2699 2726);
PAINT AQUA (-2699 2726);
FORCEPROP 2 LASTPIN (-2800 2950) $PN 3
R 1
J 0
(-2810 2960);
DISPLAY 0.723404 (-2810 2960);
PAINT MONO (-2810 2960);
FORCEPROP 2 LASTPIN (-3050 2700) $PN 5
J 2
(-3060 2710);
DISPLAY 0.723404 (-3060 2710);
PAINT MONO (-3060 2710);
FORCEPROP 2 LASTPIN (-2800 2550) $PN 4
R 1
J 2
(-2810 2540);
DISPLAY 0.723404 (-2810 2540);
PAINT MONO (-2810 2540);
FORCEPROP 1 LAST CDS_LMAN_SYM_OUTLINE -150,150,150,-150
J 0
(-2850 2750);
DISPLAY 0.468085 (-2850 2750);
PAINT GREEN (-2850 2750);
DISPLAY INVISIBLE (-2850 2750);
FORCEPROP 1 LAST NEEDS_NO_SIZE TRUE
J 0
(-2700 2641);
DISPLAY 0.468085 (-2700 2641);
PAINT GREEN (-2700 2641);
DISPLAY INVISIBLE (-2700 2641);
FORCEPROP 2 LAST CDS_LIB pure_quanta
J 0
(-2850 2750);
DISPLAY INVISIBLE (-2850 2750);
FORCEPROP 2 LAST SEC_TYPE 
J 0
(-2675 2875);
DISPLAY 1.021277 (-2675 2875);
DISPLAY INVISIBLE (-2675 2875);
FORCEPROP 1 LAST PATH I8
J 0
(-2700 2600);
DISPLAY 0.723404 (-2700 2600);
PAINT GREEN (-2700 2600);
DISPLAY INVISIBLE (-2700 2600);
FORCEPROP 2 LAST SEC 2
J 0
(-2675 2875);
DISPLAY 0.680851 (-2675 2875);
PAINT MONO (-2675 2875);
DISPLAY INVISIBLE (-2675 2875);
FORCEADD UNIVERSAL_GND..1
(-2800 2400);
FORCEPROP 3 LASTPIN (-2800 2450) SIG_NAME GND\g
J 0
(-2790 2460);
DISPLAY 0.659574 (-2790 2460);
PAINT MONO (-2790 2460);
DISPLAY INVISIBLE (-2790 2460);
FORCEPROP 1 LAST PATH I9
J 0
(-2725 2400);
DISPLAY 0.872340 (-2725 2400);
PAINT AQUA (-2725 2400);
DISPLAY INVISIBLE (-2725 2400);
FORCEPROP 1 LAST HDL_POWER GND
J 1
(-2775 2325);
DISPLAY 0.872340 (-2775 2325);
PAINT GREEN (-2775 2325);
DISPLAY INVISIBLE (-2775 2325);
FORCEPROP 2 LAST CDS_LIB logical_power
J 0
(-2800 2400);
DISPLAY INVISIBLE (-2800 2400);
FORCEADD QUANTA_TITLE_BLOCK_C..1
(5150 -1575);
FORCEPROP 0 LAST CDS_CON_LAST_MODIFIED Fri Aug 25 14:04:25 2023
J 0
(3265 -1560);
DISPLAY INVISIBLE (3265 -1560);
FORCEPROP 1 LAST CUSTOM_TXT_CDS <CON_LAST_MODIFIED>
J 0
(3265 -1560);
DISPLAY 0.978723 (3265 -1560);
FORCEPROP 2 LAST CUSTOM_TXT_CDS <XR_PAGE_TITLE>
J 0
(-2740 3675);
DISPLAY 0.638298 (-2740 3675);
PAINT PINK (-2740 3675);
DISPLAY INVISIBLE (-2740 3675);
FORCEPROP 1 LAST CUSTOM_TXT_CDS <NAME_2>
J 0
(1975 -1525);
FORCEPROP 1 LAST CUSTOM_TXT_CDS <NAME_1>
J 0
(1975 -1400);
FORCEPROP 1 LAST CUSTOM_TXT_CDS <Q_NUMBER>
J 0
(3747 -1472);
DISPLAY 1.212766 (3747 -1472);
FORCEPROP 1 LAST CUSTOM_TXT_CDS <Q_PROJ>
J 0
(2768 -1473);
DISPLAY 1.212766 (2768 -1473);
FORCEPROP 1 LAST CUSTOM_TXT_CDS <Q_REV>
J 0
(4966 -1472);
DISPLAY 1.212766 (4966 -1472);
FORCEPROP 1 LAST CUSTOM_TXT_CDS <CON_PAGE_NUM> OF <CON_TOTAL_PAGES>
J 0
(4704 -1557);
DISPLAY 0.978723 (4704 -1557);
FORCEPROP 1 LAST Q_TITLE POWER GOOD LED'S 3/5
J 0
(-4216 -1549);
DISPLAY 2.446809 (-4216 -1549);
PAINT GREEN (-4216 -1549);
FORCEPROP 1 LAST Q_DEPT 
J 1
(1387 -1526);
DISPLAY 1.957447 (1387 -1526);
PAINT GREEN (1387 -1526);
FORCEPROP 2 LAST CDS_XR_PAGE_TITLE CR-254 : @S9S_MB_2U_LIB.S9S_MB_2U(SCH_1):PAGE254
J 0
(-2740 3675);
DISPLAY 0.638298 (-2740 3675);
PAINT PINK (-2740 3675);
DISPLAY INVISIBLE (-2740 3675);
FORCEPROP 2 LAST CDS_LIB pure_quanta
J 0
(5150 -1575);
DISPLAY INVISIBLE (5150 -1575);
FORCEPROP 1 LAST CDS_LMAN_SYM_OUTLINE -9475,6775,100,-125
J 0
(5150 -1575);
DISPLAY 0.468085 (5150 -1575);
PAINT GREEN (5150 -1575);
DISPLAY INVISIBLE (5150 -1575);
FORCEPROP 2 LAST PAGE_BORDER TRUE
J 0
(-2740 3675);
DISPLAY 0.638298 (-2740 3675);
PAINT PINK (-2740 3675);
DISPLAY INVISIBLE (-2740 3675);
FORCEPROP 1 LAST COMMENT_BODY TRUE
J 0
(5162 -1588);
DISPLAY 0.978723 (5162 -1588);
PAINT GREEN (5162 -1588);
DISPLAY INVISIBLE (5162 -1588);
WIRE 16 -1 (200 3025)(200 3100);
WIRE 16 -1 (200 3025)(-300 3025);
WIRE 16 -1 (250 1800)(250 1925);
WIRE 16 -1 (250 1800)(-250 1800);
WIRE 16 -1 (4925 4350)(4925 4475);
WIRE 16 -1 (4925 4350)(4425 4350);
WIRE 16 -1 (4950 3025)(4950 3125);
WIRE 16 -1 (4950 3025)(4400 3025);
WIRE 16 -1 (4975 1775)(4975 1875);
WIRE 16 -1 (4975 1775)(4400 1775);
WIRE 16 -1 (225 4350)(225 4450);
WIRE 16 -1 (225 4350)(-325 4350);
WIRE 16 -1 (200 475)(200 575);
WIRE 16 -1 (200 475)(-300 475);
WIRE 16 -1 (1975 3775)(1975 3875);
WIRE 16 -1 (1975 2450)(1975 2550);
WIRE 16 -1 (1975 1200)(1975 1300);
WIRE 16 -1 (-2800 3775)(-2800 3875);
WIRE 16 -1 (-2800 2450)(-2800 2550);
WIRE 16 -1 (-2800 1225)(-2800 1325);
WIRE 16 -1 (-2800 -100)(-2800 0);
WIRE 74 -1 (3225 4875)(900 4875);
WIRE 74 -1 (3225 4675)(3225 4875);
WIRE 74 -1 (900 4875)(900 4675);
WIRE 74 -1 (900 4675)(3225 4675);
WIRE 74 -1 (-1475 2325)(-3875 2325);
WIRE 74 -1 (-1475 2125)(-1475 2325);
WIRE 74 -1 (-3875 2325)(-3875 2125);
WIRE 74 -1 (-3875 2125)(-1475 2125);
WIRE 16 -1 (-2800 1725)(-2800 1800);
WIRE 16 -1 (-2800 1800)(-1925 1800);
FORCEPROP 2 LAST SIG_NAME LED_PWRGD_PVCCFA_EHV_CPU1_D
J 0
(-2785 1810);
DISPLAY 0.723404 (-2785 1810);
WIRE 74 -1 (3050 2300)(900 2300);
WIRE 74 -1 (3050 2100)(3050 2300);
WIRE 74 -1 (900 2300)(900 2100);
WIRE 74 -1 (900 2100)(3050 2100);
WIRE 16 -1 (1725 2700)(875 2700);
FORCEPROP 2 LAST SIG_NAME PWRGD_PVNN_MAIN_CPU1
J 0
(940 2710);
DISPLAY 0.723404 (940 2710);
WIRE 74 -1 (3225 3550)(900 3550);
WIRE 74 -1 (3225 3350)(3225 3550);
WIRE 74 -1 (900 3550)(900 3350);
WIRE 74 -1 (900 3350)(3225 3350);
WIRE 74 -1 (-1125 1000)(-3875 1000);
WIRE 74 -1 (-1125 800)(-1125 1000);
WIRE 74 -1 (-3875 1000)(-3875 800);
WIRE 74 -1 (-3875 800)(-1125 800);
WIRE 16 -1 (-3050 1475)(-3900 1475);
FORCEPROP 2 LAST SIG_NAME PWRGD_PVCCFA_EHV_CPU1
J 0
(-3860 1485);
DISPLAY 0.723404 (-3860 1485);
WIRE 16 -1 (-2800 400)(-2800 475);
FORCEPROP 2 LAST SIG_NAME LED_PWRGD_PVCCFA_EHV_FIVRA_CPU1_D
J 0
(-3110 475);
DISPLAY 0.723404 (-3110 475);
WIRE 16 -1 (-2800 475)(-1925 475);
WIRE 16 -1 (-3050 2700)(-3900 2700);
FORCEPROP 2 LAST SIG_NAME PWRGD_PVPP_HBM_CPU1
J 0
(-3760 2710);
DISPLAY 0.723404 (-3760 2710);
WIRE 16 -1 (-2800 3025)(-1925 3025);
FORCEPROP 2 LAST SIG_NAME LED_PWRGD_PVPP_HBM_CPU1_D
J 0
(-2785 3035);
DISPLAY 0.723404 (-2785 3035);
WIRE 16 -1 (-2800 2950)(-2800 3025);
WIRE 74 -1 (-1625 3550)(-3875 3550);
WIRE 74 -1 (-1625 3350)(-1625 3550);
WIRE 74 -1 (-3875 3550)(-3875 3350);
WIRE 74 -1 (-3875 3350)(-1625 3350);
WIRE 16 -1 (-1625 3025)(-500 3025);
FORCEPROP 2 LAST SIG_NAME LED_PWRGD_PVPP_HBM_CPU1
J 0
(-1460 3035);
DISPLAY 0.723404 (-1460 3035);
WIRE 16 -1 (1725 1450)(875 1450);
FORCEPROP 2 LAST SIG_NAME PWRGD_PVCCIN_CPU1
J 0
(940 1460);
DISPLAY 0.723404 (940 1460);
WIRE 16 -1 (1975 1775)(2850 1775);
FORCEPROP 2 LAST SIG_NAME LED_PWRGD_PVCCIN_CPU1_D
J 0
(1990 1785);
DISPLAY 0.723404 (1990 1785);
WIRE 16 -1 (1975 1700)(1975 1775);
WIRE 16 -1 (1975 2950)(1975 3025);
FORCEPROP 2 LAST SIG_NAME LED_PWRGD_PVNN_MAIN_CPU1_D
J 0
(1890 3050);
DISPLAY 0.723404 (1890 3050);
WIRE 16 -1 (1975 3025)(2850 3025);
WIRE 16 -1 (1725 4025)(875 4025);
FORCEPROP 2 LAST SIG_NAME PWRGD_PVCCINFAON_CPU1
J 0
(940 4035);
DISPLAY 0.723404 (940 4035);
WIRE 16 -1 (3150 4350)(4225 4350);
FORCEPROP 2 LAST SIG_NAME LED_PWRGD_PVCCINFAON_CPU1
J 0
(3215 4350);
DISPLAY 0.723404 (3215 4350);
WIRE 16 -1 (-1625 475)(-500 475);
FORCEPROP 2 LAST SIG_NAME LED_PWRGD_PVCCFA_EHV_FIVRA_CPU1
J 0
(-1560 475);
DISPLAY 0.723404 (-1560 475);
WIRE 16 -1 (-1625 1800)(-450 1800);
FORCEPROP 2 LAST SIG_NAME LED_PWRGD_PVCCFA_EHV_CPU1
J 0
(-1460 1810);
DISPLAY 0.723404 (-1460 1810);
WIRE 16 -1 (-3050 4025)(-3900 4025);
FORCEPROP 2 LAST SIG_NAME PWRGD_PVCCD_HV_CPU1
J 0
(-3760 4035);
DISPLAY 0.723404 (-3760 4035);
WIRE 16 -1 (-1625 4350)(-525 4350);
FORCEPROP 2 LAST SIG_NAME LED_PWRGD_PVCCD_HV_CPU1
J 0
(-1460 4360);
DISPLAY 0.723404 (-1460 4360);
WIRE 16 -1 (1975 4275)(1975 4350);
FORCEPROP 2 LAST SIG_NAME LED_PWRGD_PVCCINFAON_CPU1_D
J 0
(1815 4375);
DISPLAY 0.723404 (1815 4375);
WIRE 16 -1 (1975 4350)(2850 4350);
WIRE 16 -1 (3150 3025)(4200 3025);
FORCEPROP 2 LAST SIG_NAME LED_PWRGD_PVNN_MAIN_CPU1
J 0
(3215 3050);
DISPLAY 0.723404 (3215 3050);
WIRE 16 -1 (3150 1775)(4200 1775);
FORCEPROP 2 LAST SIG_NAME LED_PWRGD_PVCCIN_CPU1
J 0
(3315 1785);
DISPLAY 0.723404 (3315 1785);
WIRE 16 -1 (-3050 150)(-3900 150);
FORCEPROP 2 LAST SIG_NAME PWRGD_PVCCFA_EHV_FIVRA_CPU1
J 0
(-3935 210);
DISPLAY 0.723404 (-3935 210);
WIRE 16 -1 (-2800 4350)(-1925 4350);
FORCEPROP 2 LAST SIG_NAME LED_PWRGD_PVCCD_HV_CPU1_D
J 0
(-2785 4360);
DISPLAY 0.723404 (-2785 4360);
WIRE 16 -1 (-2800 4275)(-2800 4350);
WIRE 74 -1 (-1625 4875)(-3875 4875);
WIRE 74 -1 (-1625 4675)(-1625 4875);
WIRE 74 -1 (-3875 4875)(-3875 4675);
WIRE 74 -1 (-3875 4675)(-1625 4675);
FORCENOTE
PWRGD_PVCCFA_EHV_FIVRA_CPU1          1 = ON
(-3750 875) 0;
DISPLAY LEFT (-3750 875);
DISPLAY 1.276596 (-3750 875);
PAINT WHITE (-3750 875);
FORCENOTE
PWRGD_PVNN_MAIN_CPU1          1 = ON
(1025 3425) 0;
DISPLAY LEFT (1025 3425);
DISPLAY 1.276596 (1025 3425);
PAINT WHITE (1025 3425);
FORCENOTE
PWRGD_PVCCFA_EHV_CPU1          1 = ON
(-3750 2200) 0;
DISPLAY LEFT (-3750 2200);
DISPLAY 1.276596 (-3750 2200);
PAINT WHITE (-3750 2200);
FORCENOTE
PWRGD_PVPP_HBM_CPU1          1 = ON
(-3750 3425) 0;
DISPLAY LEFT (-3750 3425);
DISPLAY 1.276596 (-3750 3425);
PAINT WHITE (-3750 3425);
FORCENOTE
PWRGD_PVCCIN_CPU1          1 = ON
(1025 2175) 0;
DISPLAY LEFT (1025 2175);
DISPLAY 1.276596 (1025 2175);
PAINT WHITE (1025 2175);
FORCENOTE
PWRGD_PVCCINFAON_CPU1         1 = ON
(1025 4750) 0;
DISPLAY LEFT (1025 4750);
DISPLAY 1.276596 (1025 4750);
PAINT WHITE (1025 4750);
FORCENOTE
PWRGD_PVCCD_HV_CPU1          1 = ON
(-3750 4750) 0;
DISPLAY LEFT (-3750 4750);
DISPLAY 1.276596 (-3750 4750);
PAINT WHITE (-3750 4750);
FORCENOTE
20210705 MODIFY FOR GT
(-1625 4925) 0;
DISPLAY LEFT (-1625 4925);
DISPLAY 2.510638 (-1625 4925);
PAINT PINK (-1625 4925);
QUIT
